(kicad_pcb
	(version 20241229)
	(generator "pcbnew")
	(generator_version "9.0")
	(general
		(thickness 1.62)
		(legacy_teardrops no)
	)
	(paper "A4")
	(title_block
		(title "OCuLink to 10GbE adapter")
		(date "2026-02-23")
		(rev "1.1.0")
		(company "Antmicro Ltd")
		(comment 1 "www.antmicro.com")
		(comment 9 "footprints 312-316 of 510")
	)
	(layers
		(0 "F.Cu" signal)
		(4 "In1.Cu" signal)
		(6 "In2.Cu" signal)
		(8 "In3.Cu" signal)
		(10 "In4.Cu" signal)
		(12 "In5.Cu" signal)
		(14 "In6.Cu" signal)
		(2 "B.Cu" signal)
		(9 "F.Adhes" user "F.Adhesive")
		(11 "B.Adhes" user "B.Adhesive")
		(13 "F.Paste" user)
		(15 "B.Paste" user)
		(5 "F.SilkS" user "F.Silkscreen")
		(7 "B.SilkS" user "B.Silkscreen")
		(1 "F.Mask" user)
		(3 "B.Mask" user)
		(17 "Dwgs.User" user "User.Drawings")
		(19 "Cmts.User" user "User.Comments")
		(21 "Eco1.User" user "User.Eco1")
		(23 "Eco2.User" user "User.Eco2")
		(25 "Edge.Cuts" user)
		(27 "Margin" user)
		(31 "F.CrtYd" user "F.Courtyard")
		(29 "B.CrtYd" user "B.Courtyard")
		(35 "F.Fab" user)
		(33 "B.Fab" user)
	)
	(footprint "antmicro-footprints:C_0402_1005Metric"
		(layer "B.Cu")
		(at 85.225 96.45 90)
		(descr "Capacitor SMD 0402")
		(tags "capacitor SMD 0402")
		(property "Reference" "C134"
			(at 11.58 -0.432343 90)
			(layer "B.SilkS")
			(effects
				(font
					(size 0.7 0.7)
					(thickness 0.15)
				)
				(justify right top mirror)
			)
		)
		(property "Value" "C_1u_25V_0402"
			(at -1.022927 -2.155213 90)
			(layer "B.Fab")
			(hide yes)
			(effects
				(font
					(size 0.7 0.7)
					(thickness 0.15)
				)
				(justify right top mirror)
			)
		)
		(property "Datasheet" "https://www.murata.com/products/productdetail?partno=GRM155R61E105KE11%23"
			(at 0 0 90)
			(layer "B.Fab")
			(hide yes)
			(effects
				(font
					(size 1.27 1.27)
					(thickness 0.15)
				)
				(justify mirror)
			)
		)
		(property "Description" "SMD Multilayer Ceramic Capacitor, 1 µF, 25 V, 0402 [1005 Metric], ± 10%, X5R, GRM Series"
			(at 0 0 90)
			(layer "B.Fab")
			(hide yes)
			(effects
				(font
					(size 1.27 1.27)
					(thickness 0.15)
				)
				(justify mirror)
			)
		)
		(property "MPN" "GRM155R61E105KE11J"
			(at 0 0 90)
			(unlocked yes)
			(layer "B.Fab")
			(hide yes)
			(effects
				(font
					(size 1 1)
					(thickness 0.15)
				)
				(justify mirror)
			)
		)
		(property "Manufacturer" "Murata"
			(at 0 0 90)
			(unlocked yes)
			(layer "B.Fab")
			(hide yes)
			(effects
				(font
					(size 1 1)
					(thickness 0.15)
				)
				(justify mirror)
			)
		)
		(property "License" "Apache-2.0"
			(at 0 0 90)
			(unlocked yes)
			(layer "B.Fab")
			(hide yes)
			(effects
				(font
					(size 1 1)
					(thickness 0.15)
				)
				(justify mirror)
			)
		)
		(property "Author" "Antmicro"
			(at 0 0 90)
			(unlocked yes)
			(layer "B.Fab")
			(hide yes)
			(effects
				(font
					(size 1 1)
					(thickness 0.15)
				)
				(justify mirror)
			)
		)
		(property "Val" "1u"
			(at 0 0 90)
			(unlocked yes)
			(layer "B.Fab")
			(hide yes)
			(effects
				(font
					(size 1 1)
					(thickness 0.15)
				)
				(justify mirror)
			)
		)
		(property "Voltage" "25V"
			(at 0 0 90)
			(unlocked yes)
			(layer "B.Fab")
			(hide yes)
			(effects
				(font
					(size 1 1)
					(thickness 0.15)
				)
				(justify mirror)
			)
		)
		(property "Dielectric" "X5R"
			(at 0 0 90)
			(unlocked yes)
			(layer "B.Fab")
			(hide yes)
			(effects
				(font
					(size 1 1)
					(thickness 0.15)
				)
				(justify mirror)
			)
		)
		(sheetname "/X710-AT2 power/")
		(sheetfile "x710-at2-power.kicad_sch")
		(attr smd)
		(fp_rect
			(start -0.925 0.47)
			(end 0.925 -0.47)
			(stroke
				(width 0.05)
				(type default)
			)
			(fill no)
			(layer "B.CrtYd")
		)
		(fp_line
			(start 0.504 -0.248)
			(end -0.494 -0.248)
			(stroke
				(width 0.15)
				(type solid)
			)
			(layer "B.Fab")
		)
		(fp_line
			(start -0.494 -0.248)
			(end -0.494 0.25)
			(stroke
				(width 0.15)
				(type solid)
			)
			(layer "B.Fab")
		)
		(fp_line
			(start 0.504 0.25)
			(end 0.504 -0.248)
			(stroke
				(width 0.15)
				(type solid)
			)
			(layer "B.Fab")
		)
		(fp_line
			(start -0.494 0.25)
			(end 0.504 0.25)
			(stroke
				(width 0.15)
				(type solid)
			)
			(layer "B.Fab")
		)
		(pad "1" smd roundrect
			(at -0.48 0 90)
			(size 0.59 0.64)
			(layers "B.Cu" "B.Mask" "B.Paste")
			(roundrect_rratio 0.25)
			(net 28 "GND")
			(pintype "passive")
		)
		(pad "2" smd roundrect
			(at 0.48 0 90)
			(size 0.59 0.64)
			(layers "B.Cu" "B.Mask" "B.Paste")
			(roundrect_rratio 0.25)
			(net 7 "+3V3")
			(pintype "passive")
		)
	)
	(footprint "antmicro-footprints:R_0402_1005Metric"
		(layer "B.Cu")
		(at 92.8 112.61)
		(descr "Resistor SMD 0402")
		(tags "resistor SMD 0402")
		(property "Reference" "R149"
			(at -1.45 1.72 0)
			(layer "B.SilkS")
			(effects
				(font
					(size 0.7 0.7)
					(thickness 0.15)
				)
				(justify right top mirror)
			)
		)
		(property "Value" "R_2k_0402"
			(at -1.011843 -1.772047 0)
			(layer "B.Fab")
			(effects
				(font
					(size 0.7 0.7)
					(thickness 0.15)
				)
				(justify right top mirror)
			)
		)
		(property "Datasheet" "https://www.bourns.com/docs/product-datasheets/cr.pdf"
			(at 0 0 0)
			(layer "B.Fab")
			(hide yes)
			(effects
				(font
					(size 1.27 1.27)
					(thickness 0.15)
				)
				(justify mirror)
			)
		)
		(property "Description" "SMD Chip Resistor, 2 kohm, ± 1%, 62.5 mW, 0402 [1005 Metric], Thick Film, General Purpose"
			(at 0 0 0)
			(layer "B.Fab")
			(hide yes)
			(effects
				(font
					(size 1.27 1.27)
					(thickness 0.15)
				)
				(justify mirror)
			)
		)
		(property "MPN" "CR0402-FX-2001GLF"
			(at 0 0 180)
			(unlocked yes)
			(layer "B.Fab")
			(hide yes)
			(effects
				(font
					(size 1 1)
					(thickness 0.15)
				)
				(justify mirror)
			)
		)
		(property "Manufacturer" "Bourns"
			(at 0 0 180)
			(unlocked yes)
			(layer "B.Fab")
			(hide yes)
			(effects
				(font
					(size 1 1)
					(thickness 0.15)
				)
				(justify mirror)
			)
		)
		(property "License" "Apache-2.0"
			(at 0 0 180)
			(unlocked yes)
			(layer "B.Fab")
			(hide yes)
			(effects
				(font
					(size 1 1)
					(thickness 0.15)
				)
				(justify mirror)
			)
		)
		(property "Author" "Antmicro"
			(at 0 0 180)
			(unlocked yes)
			(layer "B.Fab")
			(hide yes)
			(effects
				(font
					(size 1 1)
					(thickness 0.15)
				)
				(justify mirror)
			)
		)
		(property "Val" "2k"
			(at 0 0 180)
			(unlocked yes)
			(layer "B.Fab")
			(hide yes)
			(effects
				(font
					(size 1 1)
					(thickness 0.15)
				)
				(justify mirror)
			)
		)
		(property "Tolerance" "1%"
			(at 0 0 180)
			(unlocked yes)
			(layer "B.Fab")
			(hide yes)
			(effects
				(font
					(size 1 1)
					(thickness 0.15)
				)
				(justify mirror)
			)
		)
		(sheetname "/X710-AT2 Misc/")
		(sheetfile "x710-at2-mics.kicad_sch")
		(attr smd)
		(fp_rect
			(start -0.925 0.47)
			(end 0.925 -0.47)
			(stroke
				(width 0.05)
				(type default)
			)
			(fill no)
			(layer "B.CrtYd")
		)
		(fp_rect
			(start -0.5 0.25)
			(end 0.5 -0.25)
			(stroke
				(width 0.15)
				(type solid)
			)
			(fill no)
			(layer "B.Fab")
		)
		(fp_text user "License: Apache-2.0"
			(at -0.95 -5.169 0)
			(layer "B.Fab")
			(effects
				(font
					(size 0.7 0.7)
					(thickness 0.15)
				)
				(justify right top mirror)
			)
		)
		(fp_text user "Author: Antmicro"
			(at -0.95 -4.169 0)
			(layer "B.Fab")
			(effects
				(font
					(size 0.7 0.7)
					(thickness 0.15)
				)
				(justify right top mirror)
			)
		)
		(fp_text user "${REFERENCE}"
			(at -0.95 -3.168 0)
			(layer "B.Fab")
			(effects
				(font
					(size 0.7 0.7)
					(thickness 0.15)
				)
				(justify right top mirror)
			)
		)
		(pad "1" smd roundrect
			(at -0.48 0)
			(size 0.59 0.64)
			(layers "B.Cu" "B.Mask" "B.Paste")
			(roundrect_rratio 0.25)
			(net 384 "/X710-AT2 Misc/~{PHY_RESET}")
			(pintype "passive")
		)
		(pad "2" smd roundrect
			(at 0.48 0)
			(size 0.59 0.64)
			(layers "B.Cu" "B.Mask" "B.Paste")
			(roundrect_rratio 0.25)
			(net 18 "+1V88")
			(pintype "passive")
		)
	)
	(footprint "antmicro-footprints:C_0402_1005Metric"
		(layer "B.Cu")
		(at 80.36 105.08 90)
		(descr "Capacitor SMD 0402")
		(tags "capacitor SMD 0402")
		(property "Reference" "C84"
			(at -11.81 0.085 90)
			(layer "B.SilkS")
			(effects
				(font
					(size 0.7 0.7)
					(thickness 0.15)
				)
				(justify right top mirror)
			)
		)
		(property "Value" "C_1u_25V_0402"
			(at -1.022927 -2.155213 90)
			(layer "B.Fab")
			(hide yes)
			(effects
				(font
					(size 0.7 0.7)
					(thickness 0.15)
				)
				(justify right top mirror)
			)
		)
		(property "Datasheet" "https://www.murata.com/products/productdetail?partno=GRM155R61E105KE11%23"
			(at 0 0 90)
			(layer "B.Fab")
			(hide yes)
			(effects
				(font
					(size 1.27 1.27)
					(thickness 0.15)
				)
				(justify mirror)
			)
		)
		(property "Description" "SMD Multilayer Ceramic Capacitor, 1 µF, 25 V, 0402 [1005 Metric], ± 10%, X5R, GRM Series"
			(at 0 0 90)
			(layer "B.Fab")
			(hide yes)
			(effects
				(font
					(size 1.27 1.27)
					(thickness 0.15)
				)
				(justify mirror)
			)
		)
		(property "MPN" "GRM155R61E105KE11J"
			(at 0 0 90)
			(unlocked yes)
			(layer "B.Fab")
			(hide yes)
			(effects
				(font
					(size 1 1)
					(thickness 0.15)
				)
				(justify mirror)
			)
		)
		(property "Manufacturer" "Murata"
			(at 0 0 90)
			(unlocked yes)
			(layer "B.Fab")
			(hide yes)
			(effects
				(font
					(size 1 1)
					(thickness 0.15)
				)
				(justify mirror)
			)
		)
		(property "License" "Apache-2.0"
			(at 0 0 90)
			(unlocked yes)
			(layer "B.Fab")
			(hide yes)
			(effects
				(font
					(size 1 1)
					(thickness 0.15)
				)
				(justify mirror)
			)
		)
		(property "Author" "Antmicro"
			(at 0 0 90)
			(unlocked yes)
			(layer "B.Fab")
			(hide yes)
			(effects
				(font
					(size 1 1)
					(thickness 0.15)
				)
				(justify mirror)
			)
		)
		(property "Val" "1u"
			(at 0 0 90)
			(unlocked yes)
			(layer "B.Fab")
			(hide yes)
			(effects
				(font
					(size 1 1)
					(thickness 0.15)
				)
				(justify mirror)
			)
		)
		(property "Voltage" "25V"
			(at 0 0 90)
			(unlocked yes)
			(layer "B.Fab")
			(hide yes)
			(effects
				(font
					(size 1 1)
					(thickness 0.15)
				)
				(justify mirror)
			)
		)
		(property "Dielectric" "X5R"
			(at 0 0 90)
			(unlocked yes)
			(layer "B.Fab")
			(hide yes)
			(effects
				(font
					(size 1 1)
					(thickness 0.15)
				)
				(justify mirror)
			)
		)
		(sheetname "/X710-AT2 power/")
		(sheetfile "x710-at2-power.kicad_sch")
		(attr smd)
		(fp_rect
			(start -0.925 0.47)
			(end 0.925 -0.47)
			(stroke
				(width 0.05)
				(type default)
			)
			(fill no)
			(layer "B.CrtYd")
		)
		(fp_line
			(start 0.504 -0.248)
			(end -0.494 -0.248)
			(stroke
				(width 0.15)
				(type solid)
			)
			(layer "B.Fab")
		)
		(fp_line
			(start -0.494 -0.248)
			(end -0.494 0.25)
			(stroke
				(width 0.15)
				(type solid)
			)
			(layer "B.Fab")
		)
		(fp_line
			(start 0.504 0.25)
			(end 0.504 -0.248)
			(stroke
				(width 0.15)
				(type solid)
			)
			(layer "B.Fab")
		)
		(fp_line
			(start -0.494 0.25)
			(end 0.504 0.25)
			(stroke
				(width 0.15)
				(type solid)
			)
			(layer "B.Fab")
		)
		(pad "1" smd roundrect
			(at -0.48 0 90)
			(size 0.59 0.64)
			(layers "B.Cu" "B.Mask" "B.Paste")
			(roundrect_rratio 0.25)
			(net 28 "GND")
			(pintype "passive")
		)
		(pad "2" smd roundrect
			(at 0.48 0 90)
			(size 0.59 0.64)
			(layers "B.Cu" "B.Mask" "B.Paste")
			(roundrect_rratio 0.25)
			(net 6 "DVDD")
			(pintype "passive")
		)
	)
	(footprint "antmicro-footprints:C_0402_1005Metric"
		(layer "B.Cu")
		(at 70.85 83.93 -90)
		(descr "Capacitor SMD 0402")
		(tags "capacitor SMD 0402")
		(property "Reference" "C9"
			(at -0.63 0.45 90)
			(layer "B.SilkS")
			(effects
				(font
					(size 0.7 0.7)
					(thickness 0.15)
				)
				(justify left bottom mirror)
			)
		)
		(property "Value" "C_100n_0402"
			(at -1.022927 -2.155213 90)
			(layer "B.Fab")
			(hide yes)
			(effects
				(font
					(size 0.7 0.7)
					(thickness 0.15)
				)
				(justify left bottom mirror)
			)
		)
		(property "Datasheet" "https://www.murata.com/products/productdetail?partno=GRM155R61H104KE14%23"
			(at 0 0 90)
			(layer "B.Fab")
			(hide yes)
			(effects
				(font
					(size 1.27 1.27)
					(thickness 0.15)
				)
				(justify mirror)
			)
		)
		(property "Description" "SMD Multilayer Ceramic Capacitor, 0.1 µF, 50 V, 0402 [1005 Metric], ± 10%, X5R, GRM Series"
			(at 0 0 90)
			(layer "B.Fab")
			(hide yes)
			(effects
				(font
					(size 1.27 1.27)
					(thickness 0.15)
				)
				(justify mirror)
			)
		)
		(property "MPN" "GRM155R61H104KE14D"
			(at 0 0 270)
			(unlocked yes)
			(layer "B.Fab")
			(hide yes)
			(effects
				(font
					(size 1 1)
					(thickness 0.15)
				)
				(justify mirror)
			)
		)
		(property "Manufacturer" "Murata"
			(at 0 0 270)
			(unlocked yes)
			(layer "B.Fab")
			(hide yes)
			(effects
				(font
					(size 1 1)
					(thickness 0.15)
				)
				(justify mirror)
			)
		)
		(property "License" "Apache-2.0"
			(at 0 0 270)
			(unlocked yes)
			(layer "B.Fab")
			(hide yes)
			(effects
				(font
					(size 1 1)
					(thickness 0.15)
				)
				(justify mirror)
			)
		)
		(property "Author" "Antmicro"
			(at 0 0 270)
			(unlocked yes)
			(layer "B.Fab")
			(hide yes)
			(effects
				(font
					(size 1 1)
					(thickness 0.15)
				)
				(justify mirror)
			)
		)
		(property "Val" "100n"
			(at 0 0 270)
			(unlocked yes)
			(layer "B.Fab")
			(hide yes)
			(effects
				(font
					(size 1 1)
					(thickness 0.15)
				)
				(justify mirror)
			)
		)
		(property "Voltage" "50V"
			(at 0 0 270)
			(unlocked yes)
			(layer "B.Fab")
			(hide yes)
			(effects
				(font
					(size 1 1)
					(thickness 0.15)
				)
				(justify mirror)
			)
		)
		(property "Dielectric" "X5R"
			(at 0 0 270)
			(unlocked yes)
			(layer "B.Fab")
			(hide yes)
			(effects
				(font
					(size 1 1)
					(thickness 0.15)
				)
				(justify mirror)
			)
		)
		(sheetname "/Power/")
		(sheetfile "power.kicad_sch")
		(attr smd)
		(fp_rect
			(start -0.925 0.47)
			(end 0.925 -0.47)
			(stroke
				(width 0.05)
				(type default)
			)
			(fill no)
			(layer "B.CrtYd")
		)
		(fp_line
			(start -0.494 0.25)
			(end 0.504 0.25)
			(stroke
				(width 0.15)
				(type solid)
			)
			(layer "B.Fab")
		)
		(fp_line
			(start 0.504 0.25)
			(end 0.504 -0.248)
			(stroke
				(width 0.15)
				(type solid)
			)
			(layer "B.Fab")
		)
		(fp_line
			(start -0.494 -0.248)
			(end -0.494 0.25)
			(stroke
				(width 0.15)
				(type solid)
			)
			(layer "B.Fab")
		)
		(fp_line
			(start 0.504 -0.248)
			(end -0.494 -0.248)
			(stroke
				(width 0.15)
				(type solid)
			)
			(layer "B.Fab")
		)
		(fp_text user "${REFERENCE}"
			(at -0.939 -4.599 90)
			(layer "B.Fab")
			(effects
				(font
					(size 0.7 0.7)
					(thickness 0.15)
				)
				(justify left bottom mirror)
			)
		)
		(pad "1" smd roundrect
			(at -0.48 0 270)
			(size 0.59 0.64)
			(layers "B.Cu" "B.Mask" "B.Paste")
			(roundrect_rratio 0.25)
			(net 28 "GND")
			(pintype "passive")
		)
		(pad "2" smd roundrect
			(at 0.48 0 270)
			(size 0.59 0.64)
			(layers "B.Cu" "B.Mask" "B.Paste")
			(roundrect_rratio 0.25)
			(net 255 "/Power/+3V3_OUT")
			(pintype "passive")
		)
	)
	(footprint "antmicro-footprints:C_0402_1005Metric"
		(layer "B.Cu")
		(at 81.45 106.93 90)
		(descr "Capacitor SMD 0402")
		(tags "capacitor SMD 0402")
		(property "Reference" "C145"
			(at -12.74 0.15 90)
			(layer "B.SilkS")
			(effects
				(font
					(size 0.7 0.7)
					(thickness 0.15)
				)
				(justify right top mirror)
			)
		)
		(property "Value" "C_1u_25V_0402"
			(at -1.022927 -2.155213 90)
			(layer "B.Fab")
			(hide yes)
			(effects
				(font
					(size 0.7 0.7)
					(thickness 0.15)
				)
				(justify right top mirror)
			)
		)
		(property "Datasheet" "https://www.murata.com/products/productdetail?partno=GRM155R61E105KE11%23"
			(at 0 0 90)
			(layer "B.Fab")
			(hide yes)
			(effects
				(font
					(size 1.27 1.27)
					(thickness 0.15)
				)
				(justify mirror)
			)
		)
		(property "Description" "SMD Multilayer Ceramic Capacitor, 1 µF, 25 V, 0402 [1005 Metric], ± 10%, X5R, GRM Series"
			(at 0 0 90)
			(layer "B.Fab")
			(hide yes)
			(effects
				(font
					(size 1.27 1.27)
					(thickness 0.15)
				)
				(justify mirror)
			)
		)
		(property "MPN" "GRM155R61E105KE11J"
			(at 0 0 90)
			(unlocked yes)
			(layer "B.Fab")
			(hide yes)
			(effects
				(font
					(size 1 1)
					(thickness 0.15)
				)
				(justify mirror)
			)
		)
		(property "Manufacturer" "Murata"
			(at 0 0 90)
			(unlocked yes)
			(layer "B.Fab")
			(hide yes)
			(effects
				(font
					(size 1 1)
					(thickness 0.15)
				)
				(justify mirror)
			)
		)
		(property "License" "Apache-2.0"
			(at 0 0 90)
			(unlocked yes)
			(layer "B.Fab")
			(hide yes)
			(effects
				(font
					(size 1 1)
					(thickness 0.15)
				)
				(justify mirror)
			)
		)
		(property "Author" "Antmicro"
			(at 0 0 90)
			(unlocked yes)
			(layer "B.Fab")
			(hide yes)
			(effects
				(font
					(size 1 1)
					(thickness 0.15)
				)
				(justify mirror)
			)
		)
		(property "Val" "1u"
			(at 0 0 90)
			(unlocked yes)
			(layer "B.Fab")
			(hide yes)
			(effects
				(font
					(size 1 1)
					(thickness 0.15)
				)
				(justify mirror)
			)
		)
		(property "Voltage" "25V"
			(at 0 0 90)
			(unlocked yes)
			(layer "B.Fab")
			(hide yes)
			(effects
				(font
					(size 1 1)
					(thickness 0.15)
				)
				(justify mirror)
			)
		)
		(property "Dielectric" "X5R"
			(at 0 0 90)
			(unlocked yes)
			(layer "B.Fab")
			(hide yes)
			(effects
				(font
					(size 1 1)
					(thickness 0.15)
				)
				(justify mirror)
			)
		)
		(sheetname "/X710-AT2 power/")
		(sheetfile "x710-at2-power.kicad_sch")
		(attr smd)
		(fp_rect
			(start -0.925 0.47)
			(end 0.925 -0.47)
			(stroke
				(width 0.05)
				(type default)
			)
			(fill no)
			(layer "B.CrtYd")
		)
		(fp_line
			(start 0.504 -0.248)
			(end -0.494 -0.248)
			(stroke
				(width 0.15)
				(type solid)
			)
			(layer "B.Fab")
		)
		(fp_line
			(start -0.494 -0.248)
			(end -0.494 0.25)
			(stroke
				(width 0.15)
				(type solid)
			)
			(layer "B.Fab")
		)
		(fp_line
			(start 0.504 0.25)
			(end 0.504 -0.248)
			(stroke
				(width 0.15)
				(type solid)
			)
			(layer "B.Fab")
		)
		(fp_line
			(start -0.494 0.25)
			(end 0.504 0.25)
			(stroke
				(width 0.15)
				(type solid)
			)
			(layer "B.Fab")
		)
		(pad "1" smd roundrect
			(at -0.48 0 90)
			(size 0.59 0.64)
			(layers "B.Cu" "B.Mask" "B.Paste")
			(roundrect_rratio 0.25)
			(net 28 "GND")
			(pintype "passive")
		)
		(pad "2" smd roundrect
			(at 0.48 0 90)
			(size 0.59 0.64)
			(layers "B.Cu" "B.Mask" "B.Paste")
			(roundrect_rratio 0.25)
			(net 10 "AVDDH")
			(pintype "passive")
		)
	)
)
